# T6G (Grand Teton) — schematic netlist excerpt (pin names and nets, part order shuffled) for the footprints in the layout excerpt that follows; sources: Cadence DE-HDL packaged netlist, KiCad conversion of 04192023_DAF0TMB3IC0_F0TG_MB_C_brd_V02_OCP.brd

U263  ISL28022FRZT  ISL28022FRZ-T IC  pkg QFN16_TH_0-5_3X3XH  page 237
  A1  = INA230_3_A1
  A0  = INA230_3_A0
  \ext_clk||int\  = OCP_V3_2_P3V3_ADC_ALERT_R
  \sda||smbdat\  = SMB_INA230_3_3V3AUX_SDA_R1
  \scl|||smbclk\  = SMB_INA230_3_3V3AUX_SCL_R1
  NC0  = NC_INA230_3_NC0
  NC1  = NC_INA230_3_NC1
  NC2  = NC_INA230_3_NC2
  VCC  = P3V3_AUX
  GND  = GND
  VBUS  = P3V3_OCP_V3_2_R
  VINM  = VSENSE_P12V_INA230_3_INN
  VINP  = VSENSE_P12V_INA230_3_INP
  NC3  = NC_INA230_3_NC3
  NC4  = NC_INA230_3_NC4
  NC5  = NC_INA230_3_NC5
  TH_GND  = GND

(kicad_pcb
	(version 20260206)
	(generator "pcbnew")
	(generator_version "10.0")
	(general
		(thickness 1.6)
		(legacy_teardrops no)
	)
	(paper "A4")
	(title_block
		(title "04192023_DAF0TMB3IC0_F0TG_MB_C_brd_V02_OCP.brd")
		(comment 1 "Grand Teton / footprints 1398-1398 of 8354")
	)
	(layers
		(0 "F.Cu" signal "TOP")
		(4 "In1.Cu" signal "GND")
		(6 "In2.Cu" signal "IN1")
		(8 "In3.Cu" signal "GND1")
		(10 "In4.Cu" signal "IN2")
		(12 "In5.Cu" signal "GND2")
		(14 "In6.Cu" signal "IN3")
		(16 "In7.Cu" signal "GND3")
		(18 "In8.Cu" signal "VCC")
		(20 "In9.Cu" signal "VCC1")
		(22 "In10.Cu" signal "GND4")
		(24 "In11.Cu" signal "IN4")
		(26 "In12.Cu" signal "GND5")
		(28 "In13.Cu" signal "IN5")
		(30 "In14.Cu" signal "GND6")
		(32 "In15.Cu" signal "IN6")
		(34 "In16.Cu" signal "GND7")
		(2 "B.Cu" signal "BOTTOM")
		(9 "F.Adhes" user "F.Adhesive")
		(11 "B.Adhes" user "B.Adhesive")
		(13 "F.Paste" user "Package Geometry/Pastemask Top")
		(15 "B.Paste" user "Package Geometry/Pastemask Bottom")
		(5 "F.SilkS" user "Ref Des/Silkscreen Top")
		(7 "B.SilkS" user "Ref Des/Silkscreen Bottom")
		(1 "F.Mask" user "Board Geometry/Soldermask Top")
		(3 "B.Mask" user "Board Geometry/Soldermask Bottom")
		(17 "Dwgs.User" user "User.Drawings")
		(19 "Cmts.User" user "User.Comments")
		(21 "Eco1.User" user "User.Eco1")
		(23 "Eco2.User" user "User.Eco2")
		(25 "Edge.Cuts" user "Board Geometry/Outline")
		(27 "Margin" user)
		(31 "F.CrtYd" user "Package Geometry/Place Bound Top")
		(29 "B.CrtYd" user "Package Geometry/Place Bound Bottom")
		(35 "F.Fab" user "Ref Des/Assembly Top")
		(33 "B.Fab" user "Ref Des/Assembly Bottom")
	)
	(footprint ""
		(layer "F.Cu")
		(at 72.708262 -39.319962)
		(property "Reference" "U263"
			(at 3.21056 -1.763268 0)
			(unlocked yes)
			(layer "F.SilkS")
			(effects
				(font
					(size 0.7874 0.5842)
					(thickness 0.1524)
				)
			)
		)
		(property "Value" ""
			(at 0 0 0)
			(layer "F.Fab")
			(effects
				(font
					(size 1.27 1.27)
				)
			)
		)
		(duplicate_pad_numbers_are_jumpers no)
		(fp_line
			(start -1.500124 -1.500124)
			(end -1.004062 -1.500124)
			(stroke
				(width 0.1524)
				(type default)
			)
			(layer "F.SilkS")
		)
		(fp_line
			(start -1.500124 -1.004062)
			(end -1.500124 -1.500124)
			(stroke
				(width 0.1524)
				(type default)
			)
			(layer "F.SilkS")
		)
		(fp_line
			(start -1.500124 1.500124)
			(end -1.500124 1.004062)
			(stroke
				(width 0.1524)
				(type default)
			)
			(layer "F.SilkS")
		)
		(fp_line
			(start -1.004062 1.500124)
			(end -1.500124 1.500124)
			(stroke
				(width 0.1524)
				(type default)
			)
			(layer "F.SilkS")
		)
		(fp_line
			(start 1.004062 -1.500124)
			(end 1.500124 -1.500124)
			(stroke
				(width 0.1524)
				(type default)
			)
			(layer "F.SilkS")
		)
		(fp_line
			(start 1.500124 -1.500124)
			(end 1.500124 -1.004062)
			(stroke
				(width 0.1524)
				(type default)
			)
			(layer "F.SilkS")
		)
		(fp_line
			(start 1.500124 1.004062)
			(end 1.500124 1.500124)
			(stroke
				(width 0.1524)
				(type default)
			)
			(layer "F.SilkS")
		)
		(fp_line
			(start 1.500124 1.500124)
			(end 1.004062 1.500124)
			(stroke
				(width 0.1524)
				(type default)
			)
			(layer "F.SilkS")
		)
		(fp_poly
			(pts
				(xy -2.343912 -2.40284) (xy -3.062224 -1.684274) (xy -1.984502 -1.325118)
			)
			(stroke
				(width 0)
				(type default)
			)
			(fill yes)
			(layer "F.SilkS")
		)
		(fp_line
			(start -1.500124 -1.500124)
			(end 1.500124 -1.500124)
			(stroke
				(width 0.1)
				(type default)
			)
			(layer "F.Fab")
		)
		(fp_line
			(start -1.500124 1.500124)
			(end -1.500124 -1.500124)
			(stroke
				(width 0.1)
				(type default)
			)
			(layer "F.Fab")
		)
		(fp_line
			(start 1.500124 -1.500124)
			(end 1.500124 1.500124)
			(stroke
				(width 0.1)
				(type default)
			)
			(layer "F.Fab")
		)
		(fp_line
			(start 1.500124 1.500124)
			(end -1.500124 1.500124)
			(stroke
				(width 0.1)
				(type default)
			)
			(layer "F.Fab")
		)
		(fp_poly
			(pts
				(xy -2.847848 -1.258062) (xy -2.847848 -0.242062) (xy -1.831848 -0.750062)
			)
			(stroke
				(width 0)
				(type default)
			)
			(fill yes)
			(layer "F.Fab")
		)
		(pad "1" smd rect
			(at -1.400048 -0.750062 270)
			(size 0.2286 0.6096)
			(layers "F.Cu" "F.Mask" "F.Paste")
			(net "INA230_3_A1")
		)
		(pad "2" smd rect
			(at -1.400048 -0.249936 270)
			(size 0.2286 0.6096)
			(layers "F.Cu" "F.Mask" "F.Paste")
			(net "INA230_3_A0")
		)
		(pad "3" smd rect
			(at -1.400048 0.249936 270)
			(size 0.2286 0.6096)
			(layers "F.Cu" "F.Mask" "F.Paste")
			(net "OCP_V3_2_P3V3_ADC_ALERT_R")
		)
		(pad "4" smd rect
			(at -1.400048 0.750062 270)
			(size 0.2286 0.6096)
			(layers "F.Cu" "F.Mask" "F.Paste")
			(net "SMB_INA230_3_3V3AUX_SDA_R1")
		)
		(pad "5" smd rect
			(at -0.750062 1.400048)
			(size 0.2286 0.6096)
			(layers "F.Cu" "F.Mask" "F.Paste")
			(net "SMB_INA230_3_3V3AUX_SCL_R1")
		)
		(pad "6" smd rect
			(at -0.249936 1.400048)
			(size 0.2286 0.6096)
			(layers "F.Cu" "F.Mask" "F.Paste")
			(net "NC_INA230_3_NC0")
		)
		(pad "7" smd rect
			(at 0.249936 1.400048)
			(size 0.2286 0.6096)
			(layers "F.Cu" "F.Mask" "F.Paste")
			(net "NC_INA230_3_NC1")
		)
		(pad "8" smd rect
			(at 0.750062 1.400048)
			(size 0.2286 0.6096)
			(layers "F.Cu" "F.Mask" "F.Paste")
			(net "NC_INA230_3_NC2")
		)
		(pad "9" smd rect
			(at 1.400048 0.750062 270)
			(size 0.2286 0.6096)
			(layers "F.Cu" "F.Mask" "F.Paste")
			(net "P3V3_AUX")
		)
		(pad "10" smd rect
			(at 1.400048 0.249936 270)
			(size 0.2286 0.6096)
			(layers "F.Cu" "F.Mask" "F.Paste")
			(net "GND")
		)
		(pad "11" smd rect
			(at 1.400048 -0.249936 270)
			(size 0.2286 0.6096)
			(layers "F.Cu" "F.Mask" "F.Paste")
			(net "P3V3_OCP_V3_2_R")
		)
		(pad "12" smd rect
			(at 1.400048 -0.750062 270)
			(size 0.2286 0.6096)
			(layers "F.Cu" "F.Mask" "F.Paste")
			(net "VSENSE_P12V_INA230_3_INN")
		)
		(pad "13" smd rect
			(at 0.750062 -1.400048)
			(size 0.2286 0.6096)
			(layers "F.Cu" "F.Mask" "F.Paste")
			(net "VSENSE_P12V_INA230_3_INP")
		)
		(pad "14" smd rect
			(at 0.249936 -1.400048)
			(size 0.2286 0.6096)
			(layers "F.Cu" "F.Mask" "F.Paste")
			(net "NC_INA230_3_NC3")
		)
		(pad "15" smd rect
			(at -0.249936 -1.400048)
			(size 0.2286 0.6096)
			(layers "F.Cu" "F.Mask" "F.Paste")
			(net "NC_INA230_3_NC4")
		)
		(pad "16" smd rect
			(at -0.750062 -1.400048)
			(size 0.2286 0.6096)
			(layers "F.Cu" "F.Mask" "F.Paste")
			(net "NC_INA230_3_NC5")
		)
		(pad "TH" smd rect
			(at 0 0)
			(size 1.7018 1.7018)
			(layers "F.Cu" "F.Mask" "F.Paste")
			(net "GND")
		)
		(zone
			(layer "F.Cu")
			(hatch none 0.5)
			(connect_pads
				(clearance 0)
			)
			(min_thickness 0.25)
			(keepout
				(tracks not_allowed)
				(vias allowed)
				(pads allowed)
				(copperpour not_allowed)
				(footprints allowed)
			)
			(placement
				(enabled no)
				(sheetname "")
			)
			(fill
				(thermal_gap 0.5)
				(thermal_bridge_width 0.5)
				(island_removal_mode 0)
			)
			(polygon
				(pts
					(xy 71.663814 -39.345362) (xy 71.663814 -40.36441) (xy 73.75271 -40.36441) (xy 73.75271 -38.275514)
					(xy 71.663814 -38.275514) (xy 71.663814 -39.319962) (xy 71.806562 -39.319962) (xy 71.806562 -38.418262)
					(xy 73.609962 -38.418262) (xy 73.609962 -40.221662) (xy 71.806562 -40.221662) (xy 71.806562 -39.345362)
				)
			)
		)
	)
)
